(kicad_pcb
	(version 20260206)
	(generator "pcbnew")
	(generator_version "10.0")
	(general
		(thickness 1.6)
		(legacy_teardrops no)
	)
	(paper "A4")
	(title_block
		(title "Wiwynn_Tioga_Pass_MB.brd")
		(comment 1 "Tioga Pass / footprints 1178-1183 of 4770")
	)
	(layers
		(0 "F.Cu" signal "TOP")
		(4 "In1.Cu" signal "L2GND")
		(6 "In2.Cu" signal "L3")
		(8 "In3.Cu" signal "L4GND")
		(10 "In4.Cu" signal "L5")
		(12 "In5.Cu" signal "L6GND")
		(14 "In6.Cu" signal "L7VCC")
		(16 "In7.Cu" signal "L8VCC")
		(18 "In8.Cu" signal "L9GND")
		(20 "In9.Cu" signal "L10")
		(22 "In10.Cu" signal "L11GND")
		(24 "In11.Cu" signal "L12")
		(26 "In12.Cu" signal "L13GND")
		(2 "B.Cu" signal "BOTTOM")
		(9 "F.Adhes" user "F.Adhesive")
		(11 "B.Adhes" user "B.Adhesive")
		(13 "F.Paste" user "Package Geometry/Pastemask Top")
		(15 "B.Paste" user "Package Geometry/Pastemask Bottom")
		(5 "F.SilkS" user "Ref Des/Silkscreen Top")
		(7 "B.SilkS" user "Ref Des/Silkscreen Bottom")
		(1 "F.Mask" user "Board Geometry/Soldermask Top")
		(3 "B.Mask" user "Board Geometry/Soldermask Bottom")
		(17 "Dwgs.User" user "User.Drawings")
		(19 "Cmts.User" user "User.Comments")
		(21 "Eco1.User" user "User.Eco1")
		(23 "Eco2.User" user "User.Eco2")
		(25 "Edge.Cuts" user "Board Geometry/Outline")
		(27 "Margin" user)
		(31 "F.CrtYd" user "Package Geometry/Place Bound Top")
		(29 "B.CrtYd" user "Package Geometry/Place Bound Bottom")
		(35 "F.Fab" user "Ref Des/Assembly Top")
		(33 "B.Fab" user "Ref Des/Assembly Bottom")
	)
	(footprint ""
		(layer "F.Cu")
		(at 269.559532 -3.3528 90)
		(property "Reference" "C5G16"
			(at 1.848866 0.752348 90)
			(unlocked yes)
			(layer "F.SilkS")
			(effects
				(font
					(size 1.27 0.9652)
					(thickness 0.1524)
				)
			)
		)
		(property "Value" ""
			(at 0 0 90)
			(layer "F.Fab")
			(effects
				(font
					(size 1.27 1.27)
				)
			)
		)
		(duplicate_pad_numbers_are_jumpers no)
		(fp_rect
			(start -0.500126 1.598422)
			(end 0.500126 -0.201422)
			(stroke
				(width 0)
				(type default)
			)
			(fill no)
			(layer "F.CrtYd")
		)
		(fp_line
			(start 0.500126 -0.201422)
			(end 0.500126 1.598422)
			(stroke
				(width 0.1)
				(type default)
			)
			(layer "F.Fab")
		)
		(fp_line
			(start -0.500126 -0.201422)
			(end 0.500126 -0.201422)
			(stroke
				(width 0.1)
				(type default)
			)
			(layer "F.Fab")
		)
		(fp_line
			(start 0.500126 1.598422)
			(end -0.500126 1.598422)
			(stroke
				(width 0.1)
				(type default)
			)
			(layer "F.Fab")
		)
		(fp_line
			(start -0.500126 1.598422)
			(end -0.500126 -0.201422)
			(stroke
				(width 0.1)
				(type default)
			)
			(layer "F.Fab")
		)
		(pad "1" smd rect
			(at 0 0)
			(size 0.889 0.9906)
			(layers "F.Cu" "F.Mask" "F.Paste")
			(net "PVDDQ_ABC")
		)
		(pad "2" smd rect
			(at 0 1.397)
			(size 0.889 0.9906)
			(layers "F.Cu" "F.Mask" "F.Paste")
			(net "GND")
		)
		(zone
			(layer "F.Cu")
			(hatch none 0.5)
			(connect_pads
				(clearance 0)
			)
			(min_thickness 0.25)
			(keepout
				(tracks allowed)
				(vias not_allowed)
				(pads allowed)
				(copperpour not_allowed)
				(footprints allowed)
			)
			(placement
				(enabled no)
				(sheetname "")
			)
			(fill
				(thermal_gap 0.5)
				(thermal_bridge_width 0.5)
				(island_removal_mode 0)
			)
			(polygon
				(pts
					(xy 270.512032 -2.8575) (xy 270.512032 -3.8481) (xy 270.004032 -3.8481) (xy 270.004032 -2.8575)
				)
			)
		)
		(zone
			(layer "F.Cu")
			(hatch none 0.5)
			(connect_pads
				(clearance 0)
			)
			(min_thickness 0.25)
			(keepout
				(tracks not_allowed)
				(vias allowed)
				(pads allowed)
				(copperpour not_allowed)
				(footprints allowed)
			)
			(placement
				(enabled no)
				(sheetname "")
			)
			(fill
				(thermal_gap 0.5)
				(thermal_bridge_width 0.5)
				(island_removal_mode 0)
			)
			(polygon
				(pts
					(xy 270.512032 -2.8575) (xy 270.512032 -3.8481) (xy 270.004032 -3.8481) (xy 270.004032 -2.8575)
				)
			)
		)
	)
	(footprint ""
		(layer "F.Cu")
		(at 341.996776 -11.798046 90)
		(property "Reference" "RF15"
			(at -0.8382 -0.67818 90)
			(unlocked yes)
			(layer "F.SilkS")
			(effects
				(font
					(size 0.4064 0.254)
					(thickness 0.1524)
				)
				(justify left)
			)
		)
		(property "Value" ""
			(at 0 0 90)
			(layer "F.Fab")
			(effects
				(font
					(size 1.27 1.27)
				)
			)
		)
		(duplicate_pad_numbers_are_jumpers no)
		(fp_poly
			(pts
				(xy -0.2794 -0.1016) (xy 0.2794 -0.1016) (xy 0.2794 0.9906) (xy -0.2794 0.9906)
			)
			(stroke
				(width 0)
				(type default)
			)
			(fill no)
			(layer "F.CrtYd")
		)
		(fp_line
			(start 0.2794 -0.1016)
			(end -0.2794 -0.1016)
			(stroke
				(width 0.1)
				(type default)
			)
			(layer "F.Fab")
		)
		(fp_line
			(start -0.2794 -0.1016)
			(end -0.2794 0.9906)
			(stroke
				(width 0.1)
				(type default)
			)
			(layer "F.Fab")
		)
		(fp_line
			(start 0.2794 0.9906)
			(end 0.2794 -0.1016)
			(stroke
				(width 0.1)
				(type default)
			)
			(layer "F.Fab")
		)
		(fp_line
			(start -0.2794 0.9906)
			(end 0.2794 0.9906)
			(stroke
				(width 0.1)
				(type default)
			)
			(layer "F.Fab")
		)
		(pad "1" smd rect
			(at 0 0 90)
			(size 0.508 0.508)
			(layers "F.Cu" "F.Mask" "F.Paste")
			(net "VR_PVDDQ_ABC_AIREF1")
		)
		(pad "2" smd rect
			(at 0 0.889 90)
			(size 0.508 0.508)
			(layers "F.Cu" "F.Mask" "F.Paste")
			(net "ISENSE_PVDDQ_ABC_PH1_IMON")
		)
		(zone
			(layer "F.Cu")
			(hatch none 0.5)
			(connect_pads
				(clearance 0)
			)
			(min_thickness 0.25)
			(keepout
				(tracks allowed)
				(vias not_allowed)
				(pads allowed)
				(copperpour not_allowed)
				(footprints allowed)
			)
			(placement
				(enabled no)
				(sheetname "")
			)
			(fill
				(thermal_gap 0.5)
				(thermal_bridge_width 0.5)
				(island_removal_mode 0)
			)
			(polygon
				(pts
					(xy 342.250776 -11.544046) (xy 342.250776 -12.052046) (xy 342.631776 -12.052046) (xy 342.631776 -11.544046)
				)
			)
		)
		(zone
			(layer "F.Cu")
			(hatch none 0.5)
			(connect_pads
				(clearance 0)
			)
			(min_thickness 0.25)
			(keepout
				(tracks not_allowed)
				(vias allowed)
				(pads allowed)
				(copperpour not_allowed)
				(footprints allowed)
			)
			(placement
				(enabled no)
				(sheetname "")
			)
			(fill
				(thermal_gap 0.5)
				(thermal_bridge_width 0.5)
				(island_removal_mode 0)
			)
			(polygon
				(pts
					(xy 342.631776 -11.544046) (xy 342.631776 -12.052046) (xy 342.250776 -12.052046) (xy 342.250776 -11.544046)
				)
			)
		)
	)
	(footprint ""
		(layer "F.Cu")
		(at 480.335844 -150.39467 180)
		(property "Reference" "J8C1"
			(at 5.66801 2.02184 90)
			(unlocked yes)
			(layer "F.SilkS")
			(effects
				(font
					(size 0.7874 0.5842)
					(thickness 0.1524)
				)
			)
		)
		(property "Value" ""
			(at 0 0 180)
			(layer "F.Fab")
			(effects
				(font
					(size 1.27 1.27)
				)
			)
		)
		(duplicate_pad_numbers_are_jumpers no)
		(fp_line
			(start 1.27 6.54939)
			(end -1.27 6.54939)
			(stroke
				(width 0.1524)
				(type default)
			)
			(layer "F.SilkS")
		)
		(fp_line
			(start 1.27 -1.46939)
			(end 1.27 6.54939)
			(stroke
				(width 0.1524)
				(type default)
			)
			(layer "F.SilkS")
		)
		(fp_line
			(start -1.27 6.54939)
			(end -1.27 -1.46939)
			(stroke
				(width 0.1524)
				(type default)
			)
			(layer "F.SilkS")
		)
		(fp_line
			(start -1.27 -1.46939)
			(end 1.27 -1.46939)
			(stroke
				(width 0.1524)
				(type default)
			)
			(layer "F.SilkS")
		)
		(fp_poly
			(pts
				(xy 2.662682 0.546862) (xy 2.662682 1.562862) (xy 1.392682 1.054862)
			)
			(stroke
				(width 0)
				(type default)
			)
			(fill yes)
			(layer "F.SilkS")
		)
		(fp_poly
			(pts
				(xy 2.148078 -0.52197) (xy 2.148078 0.49403) (xy 0.878078 -0.01397)
			)
			(stroke
				(width 0)
				(type default)
			)
			(fill yes)
			(layer "B.SilkS")
		)
		(fp_poly
			(pts
				(xy 1.27 6.54939) (xy 1.27 -1.46939) (xy -1.27 -1.46939) (xy -1.27 6.54939)
			)
			(stroke
				(width 0)
				(type default)
			)
			(fill no)
			(layer "F.CrtYd")
		)
		(fp_poly
			(pts
				(xy -3.17246 0.38862) (xy -3.17246 -0.62738) (xy -1.90246 -0.11938)
			)
			(stroke
				(width 0)
				(type default)
			)
			(fill yes)
			(layer "B.Fab")
		)
		(fp_line
			(start 1.27 6.54939)
			(end -1.27 6.54939)
			(stroke
				(width 0.1)
				(type default)
			)
			(layer "F.Fab")
		)
		(fp_line
			(start 1.27 -1.46939)
			(end 1.27 6.54939)
			(stroke
				(width 0.1)
				(type default)
			)
			(layer "F.Fab")
		)
		(fp_line
			(start -1.27 6.54939)
			(end -1.27 -1.46939)
			(stroke
				(width 0.1)
				(type default)
			)
			(layer "F.Fab")
		)
		(fp_line
			(start -1.27 -1.46939)
			(end 1.27 -1.46939)
			(stroke
				(width 0.1)
				(type default)
			)
			(layer "F.Fab")
		)
		(fp_poly
			(pts
				(xy -3.17246 0.38862) (xy -3.17246 -0.62738) (xy -1.90246 -0.11938)
			)
			(stroke
				(width 0)
				(type default)
			)
			(fill yes)
			(layer "F.Fab")
		)
		(fp_text user "3"
			(at 2.036064 6.67004 0)
			(unlocked yes)
			(layer "F.SilkS")
			(effects
				(font
					(size 0.7874 0.5842)
					(thickness 0.1524)
				)
				(justify left)
			)
		)
		(fp_text user "3"
			(at 0.258064 6.604 180)
			(unlocked yes)
			(layer "B.SilkS")
			(effects
				(font
					(size 0.7874 0.5842)
					(thickness 0.1524)
				)
				(justify left mirror)
			)
		)
		(fp_text user "3"
			(at 0.247904 6.604 180)
			(unlocked yes)
			(layer "B.Fab")
			(effects
				(font
					(size 0.7874 0.5842)
					(thickness 0.1524)
				)
				(justify left mirror)
			)
		)
		(fp_text user "3"
			(at 1.964944 2.986024 0)
			(unlocked yes)
			(layer "F.Fab")
			(effects
				(font
					(size 0.7874 0.5842)
					(thickness 0.1524)
				)
				(justify left)
			)
		)
		(pad "1" thru_hole rect
			(at 0 0 180)
			(size 1.524 1.524)
			(drill 1.143)
			(layers "*.Cu" "*.Mask")
			(remove_unused_layers no)
			(net "SMB_HOST_STBY_LVC3_SDA")
			(clearance 0.127)
			(thermal_gap 0.127)
			(padstack
				(mode front_inner_back)
				(layer "Inner"
					(shape circle)
					(size 1.524 1.524)
					(clearance 0.127)
				)
				(layer "B.Cu"
					(shape rect)
					(size 1.524 1.524)
					(clearance 0.127)
				)
			)
		)
		(pad "2" thru_hole circle
			(at 0 2.54 180)
			(size 1.524 1.524)
			(drill 1.143)
			(layers "*.Cu" "*.Mask")
			(remove_unused_layers no)
			(net "GND")
			(clearance 0.127)
			(thermal_gap 0.127)
		)
		(pad "3" thru_hole circle
			(at 0 5.08 180)
			(size 1.524 1.524)
			(drill 1.143)
			(layers "*.Cu" "*.Mask")
			(remove_unused_layers no)
			(net "SMB_HOST_STBY_LVC3_SCL")
			(clearance 0.127)
			(thermal_gap 0.127)
		)
	)
	(footprint ""
		(layer "F.Cu")
		(at 221.991936 11.952478 -90)
		(property "Reference" "T1P5"
			(at 0 0 270)
			(layer "F.SilkS")
			(hide yes)
			(effects
				(font
					(size 1.27 1.27)
				)
			)
		)
		(property "Value" "*"
			(at -3.302 1.12395 270)
			(unlocked yes)
			(layer "F.Fab")
			(hide yes)
			(effects
				(font
					(size 0.889 0.889)
					(thickness 0.1524)
				)
			)
		)
		(property "Device Type" "TPAD-DIFF-4P-GP_DISCRET-GB3-TPA"
			(at -3.302 -0.40005 270)
			(unlocked yes)
			(layer "F.Fab")
			(hide yes)
			(effects
				(font
					(size 0.889 0.889)
					(thickness 0.1524)
				)
			)
		)
		(duplicate_pad_numbers_are_jumpers no)
		(fp_line
			(start -2.286 2.286)
			(end 2.286 2.286)
			(stroke
				(width 0.1524)
				(type default)
			)
			(layer "F.SilkS")
		)
		(fp_line
			(start 2.286 2.286)
			(end 2.286 -2.286)
			(stroke
				(width 0.1524)
				(type default)
			)
			(layer "F.SilkS")
		)
		(fp_line
			(start -2.286 -2.286)
			(end -2.286 2.286)
			(stroke
				(width 0.1524)
				(type default)
			)
			(layer "F.SilkS")
		)
		(fp_line
			(start 2.286 -2.286)
			(end -2.286 -2.286)
			(stroke
				(width 0.1524)
				(type default)
			)
			(layer "F.SilkS")
		)
		(fp_line
			(start -2.413 -2.413)
			(end -2.413 -1.143)
			(stroke
				(width 0.4064)
				(type default)
			)
			(layer "F.SilkS")
		)
		(fp_line
			(start -1.143 -2.413)
			(end -2.413 -2.413)
			(stroke
				(width 0.4064)
				(type default)
			)
			(layer "F.SilkS")
		)
		(fp_rect
			(start -2.54 2.54)
			(end 2.54 -2.54)
			(stroke
				(width 0)
				(type default)
			)
			(fill no)
			(layer "F.CrtYd")
		)
		(fp_rect
			(start -2.54 2.54)
			(end 2.54 -2.54)
			(stroke
				(width 0)
				(type default)
			)
			(fill no)
			(layer "F.Fab")
		)
		(pad "1" thru_hole circle
			(at -1.27 -1.27 270)
			(size 1.524 1.524)
			(drill 0.9144)
			(layers "*.Cu" "*.Mask")
			(remove_unused_layers no)
			(net "L12_85OHM_6INCH_DP")
			(clearance -0.0508)
			(thermal_gap 0.127)
			(padstack
				(mode front_inner_back)
				(layer "Inner"
					(shape circle)
					(size 1.1684 1.1684)
					(clearance 0.127)
				)
				(layer "B.Cu"
					(shape circle)
					(size 1.524 1.524)
					(clearance -0.0508)
				)
			)
		)
		(pad "2" thru_hole circle
			(at 1.27 -1.27 270)
			(size 1.524 1.524)
			(drill 0.9144)
			(layers "*.Cu" "*.Mask")
			(remove_unused_layers no)
			(net "L12_85OHM_6INCH_DN")
			(clearance -0.0508)
			(thermal_gap 0.127)
			(padstack
				(mode front_inner_back)
				(layer "Inner"
					(shape circle)
					(size 1.1684 1.1684)
					(clearance 0.127)
				)
				(layer "B.Cu"
					(shape circle)
					(size 1.524 1.524)
					(clearance -0.0508)
				)
			)
		)
		(pad "GND1" thru_hole rect
			(at -1.27 1.27 270)
			(size 1.524 1.524)
			(drill 0.9144)
			(layers "*.Cu" "*.Mask")
			(remove_unused_layers no)
			(net "GND")
			(clearance -0.0508)
			(thermal_gap 0.127)
			(padstack
				(mode front_inner_back)
				(layer "Inner"
					(shape circle)
					(size 1.1684 1.1684)
					(clearance 0.127)
				)
				(layer "B.Cu"
					(shape rect)
					(size 1.524 1.524)
					(clearance -0.0508)
				)
			)
		)
		(pad "GND2" thru_hole rect
			(at 1.27 1.27 270)
			(size 1.524 1.524)
			(drill 0.9144)
			(layers "*.Cu" "*.Mask")
			(remove_unused_layers no)
			(net "GND")
			(clearance -0.0508)
			(thermal_gap 0.127)
			(padstack
				(mode front_inner_back)
				(layer "Inner"
					(shape circle)
					(size 1.1684 1.1684)
					(clearance 0.127)
				)
				(layer "B.Cu"
					(shape rect)
					(size 1.524 1.524)
					(clearance -0.0508)
				)
			)
		)
	)
	(footprint ""
		(layer "F.Cu")
		(at 7.333234 -113.840514 90)
		(property "Reference" "R10W5"
			(at 1.47828 0.78994 0)
			(unlocked yes)
			(layer "F.SilkS")
			(effects
				(font
					(size 0.4064 0.254)
					(thickness 0.1524)
				)
			)
		)
		(property "Value" ""
			(at 0 0 90)
			(layer "F.Fab")
			(effects
				(font
					(size 1.27 1.27)
				)
			)
		)
		(duplicate_pad_numbers_are_jumpers no)
		(fp_poly
			(pts
				(xy -0.7239 -0.2159) (xy 0.7239 -0.2159) (xy 0.7239 1.9939) (xy -0.7239 1.9939)
			)
			(stroke
				(width 0)
				(type default)
			)
			(fill no)
			(layer "F.CrtYd")
		)
		(fp_line
			(start 0.7239 -0.2159)
			(end -0.7239 -0.2159)
			(stroke
				(width 0.1)
				(type default)
			)
			(layer "F.Fab")
		)
		(fp_line
			(start -0.7239 -0.2159)
			(end -0.7239 1.9939)
			(stroke
				(width 0.1)
				(type default)
			)
			(layer "F.Fab")
		)
		(fp_line
			(start 0.7239 1.9939)
			(end 0.7239 -0.2159)
			(stroke
				(width 0.1)
				(type default)
			)
			(layer "F.Fab")
		)
		(fp_line
			(start -0.7239 1.9939)
			(end 0.7239 1.9939)
			(stroke
				(width 0.1)
				(type default)
			)
			(layer "F.Fab")
		)
		(pad "1" smd rect
			(at 0 0 90)
			(size 1.27 1.016)
			(layers "F.Cu" "F.Mask" "F.Paste")
			(net "P12V_FAN")
		)
		(pad "2" smd rect
			(at 0 1.778 90)
			(size 1.27 1.016)
			(layers "F.Cu" "F.Mask" "F.Paste")
			(net "P12V_PUMP")
		)
		(zone
			(layer "F.Cu")
			(hatch none 0.5)
			(connect_pads
				(clearance 0)
			)
			(min_thickness 0.25)
			(keepout
				(tracks not_allowed)
				(vias allowed)
				(pads allowed)
				(copperpour not_allowed)
				(footprints allowed)
			)
			(placement
				(enabled no)
				(sheetname "")
			)
			(fill
				(thermal_gap 0.5)
				(thermal_bridge_width 0.5)
				(island_removal_mode 0)
			)
			(polygon
				(pts
					(xy 7.841234 -114.475514) (xy 8.603234 -114.475514) (xy 8.603234 -114.386614) (xy 8.603234 -113.205514)
					(xy 7.841234 -113.205514)
				)
			)
		)
	)
	(footprint ""
		(layer "F.Cu")
		(at 313.299602 -34.652458)
		(property "Reference" "Q1W6"
			(at -0.229362 -1.59512 0)
			(unlocked yes)
			(layer "F.SilkS")
			(effects
				(font
					(size 1.27 0.9652)
					(thickness 0.1524)
				)
				(justify left)
			)
		)
		(property "Value" ""
			(at 0 0 0)
			(layer "F.Fab")
			(effects
				(font
					(size 1.27 1.27)
				)
			)
		)
		(duplicate_pad_numbers_are_jumpers no)
		(fp_line
			(start 0.381 0.635)
			(end 0.381 1.27)
			(stroke
				(width 0.1524)
				(type default)
			)
			(layer "F.SilkS")
		)
		(fp_line
			(start 0.9525 -0.5715)
			(end 1.778 -0.5715)
			(stroke
				(width 0.1524)
				(type default)
			)
			(layer "F.SilkS")
		)
		(fp_line
			(start 0.9525 2.4765)
			(end 1.778 2.4765)
			(stroke
				(width 0.1524)
				(type default)
			)
			(layer "F.SilkS")
		)
		(fp_line
			(start 1.778 -0.5715)
			(end 1.778 0.3175)
			(stroke
				(width 0.1524)
				(type default)
			)
			(layer "F.SilkS")
		)
		(fp_line
			(start 1.778 2.4765)
			(end 1.778 1.5875)
			(stroke
				(width 0.1524)
				(type default)
			)
			(layer "F.SilkS")
		)
		(fp_circle
			(center -0.37846 -0.885952)
			(end -0.25146 -0.885952)
			(stroke
				(width 0.254)
				(type default)
			)
			(fill no)
			(layer "F.SilkS")
		)
		(fp_poly
			(pts
				(xy 1.778 2.4765) (xy 0.381 2.4765) (xy 0.381 -0.5715) (xy 1.778 -0.5715)
			)
			(stroke
				(width 0)
				(type default)
			)
			(fill no)
			(layer "F.CrtYd")
		)
		(fp_line
			(start 0.381 -0.5715)
			(end 0.381 2.4765)
			(stroke
				(width 0.1)
				(type default)
			)
			(layer "F.Fab")
		)
		(fp_line
			(start 0.381 2.4765)
			(end 1.778 2.4765)
			(stroke
				(width 0.1)
				(type default)
			)
			(layer "F.Fab")
		)
		(fp_line
			(start 1.778 -0.5715)
			(end 0.381 -0.5715)
			(stroke
				(width 0.1)
				(type default)
			)
			(layer "F.Fab")
		)
		(fp_line
			(start 1.778 2.4765)
			(end 1.778 -0.5715)
			(stroke
				(width 0.1)
				(type default)
			)
			(layer "F.Fab")
		)
		(fp_circle
			(center -0.37846 -0.885952)
			(end -0.25146 -0.885952)
			(stroke
				(width 0.254)
				(type default)
			)
			(fill no)
			(layer "F.Fab")
		)
		(pad "1" smd rect
			(at 0 0)
			(size 1.143 0.508)
			(layers "F.Cu" "F.Mask" "F.Paste")
			(net "FM_ADR_COMPLETE_CPU1_R")
		)
		(pad "2" smd rect
			(at 0 1.905)
			(size 1.143 0.508)
			(layers "F.Cu" "F.Mask" "F.Paste")
			(net "GND")
		)
		(pad "3" smd rect
			(at 2.159 0.9525)
			(size 1.143 0.508)
			(layers "F.Cu" "F.Mask" "F.Paste")
			(net "FM_ADR_COMPLETE_CPU1_N")
		)
	)
)
